# BASEBOARD_FAB2 (Tioga Pass) — schematic netlist excerpt (pin names and nets, part order shuffled) for the footprints in the layout excerpt that follows; sources: Cadence DE-HDL packaged netlist, KiCad conversion of Wiwynn_Tioga_Pass_MB.brd

C3U7  CAP  10UF 16V 10% X6S  pkg 0805  page 216 : A = VR_FET_SW_P12V_STBY_PVDDQ_ABC ; B = GND
C3T1  CAP_A  47UF 4V 20% X5R  pkg 0603V  page 194 : A = P1V8_MCP_CPU0 ; B = GND
R6N11  RES  0.0 5% CHIP  pkg 0402  page 21 : A = SVID_DIO0_CPU0 ; B = SVID_DIO0_CPU0_R

(kicad_pcb
	(version 20260206)
	(generator "pcbnew")
	(generator_version "10.0")
	(general
		(thickness 1.6)
		(legacy_teardrops no)
	)
	(paper "A4")
	(title_block
		(title "Wiwynn_Tioga_Pass_MB.brd")
		(comment 1 "Tioga Pass / footprints 3363-3365 of 4770")
	)
	(layers
		(0 "F.Cu" signal "TOP")
		(4 "In1.Cu" signal "L2GND")
		(6 "In2.Cu" signal "L3")
		(8 "In3.Cu" signal "L4GND")
		(10 "In4.Cu" signal "L5")
		(12 "In5.Cu" signal "L6GND")
		(14 "In6.Cu" signal "L7VCC")
		(16 "In7.Cu" signal "L8VCC")
		(18 "In8.Cu" signal "L9GND")
		(20 "In9.Cu" signal "L10")
		(22 "In10.Cu" signal "L11GND")
		(24 "In11.Cu" signal "L12")
		(26 "In12.Cu" signal "L13GND")
		(2 "B.Cu" signal "BOTTOM")
		(9 "F.Adhes" user "F.Adhesive")
		(11 "B.Adhes" user "B.Adhesive")
		(13 "F.Paste" user "Package Geometry/Pastemask Top")
		(15 "B.Paste" user "Package Geometry/Pastemask Bottom")
		(5 "F.SilkS" user "Ref Des/Silkscreen Top")
		(7 "B.SilkS" user "Ref Des/Silkscreen Bottom")
		(1 "F.Mask" user "Board Geometry/Soldermask Top")
		(3 "B.Mask" user "Board Geometry/Soldermask Bottom")
		(17 "Dwgs.User" user "User.Drawings")
		(19 "Cmts.User" user "User.Comments")
		(21 "Eco1.User" user "User.Eco1")
		(23 "Eco2.User" user "User.Eco2")
		(25 "Edge.Cuts" user "Board Geometry/Outline")
		(27 "Margin" user)
		(31 "F.CrtYd" user "Package Geometry/Place Bound Top")
		(29 "B.CrtYd" user "Package Geometry/Place Bound Bottom")
		(35 "F.Fab" user "Ref Des/Assembly Top")
		(33 "B.Fab" user "Ref Des/Assembly Bottom")
	)
	(footprint ""
		(layer "B.Cu")
		(at 347.469206 2.694178 -90)
		(property "Reference" "C3U7"
			(at 0 0 90)
			(layer "B.SilkS")
			(hide yes)
			(effects
				(font
					(size 1.27 1.27)
				)
				(justify mirror)
			)
		)
		(property "Value" ""
			(at 0 0 90)
			(layer "B.Fab")
			(effects
				(font
					(size 1.27 1.27)
				)
				(justify mirror)
			)
		)
		(duplicate_pad_numbers_are_jumpers no)
		(fp_rect
			(start 0.7239 1.9939)
			(end -0.7239 -0.2159)
			(stroke
				(width 0)
				(type default)
			)
			(fill no)
			(layer "B.CrtYd")
		)
		(fp_line
			(start -0.7239 1.9939)
			(end -0.7239 -0.2159)
			(stroke
				(width 0.1)
				(type default)
			)
			(layer "B.Fab")
		)
		(fp_line
			(start 0.7239 1.9939)
			(end -0.7239 1.9939)
			(stroke
				(width 0.1)
				(type default)
			)
			(layer "B.Fab")
		)
		(fp_line
			(start -0.7239 -0.2159)
			(end 0.7239 -0.2159)
			(stroke
				(width 0.1)
				(type default)
			)
			(layer "B.Fab")
		)
		(fp_line
			(start 0.7239 -0.2159)
			(end 0.7239 1.9939)
			(stroke
				(width 0.1)
				(type default)
			)
			(layer "B.Fab")
		)
		(pad "1" smd rect
			(at 0 0 90)
			(size 1.27 1.016)
			(layers "B.Cu" "B.Mask" "B.Paste")
			(net "VR_FET_SW_P12V_STBY_PVDDQ_ABC")
		)
		(pad "2" smd rect
			(at 0 1.778 90)
			(size 1.27 1.016)
			(layers "B.Cu" "B.Mask" "B.Paste")
			(net "GND")
		)
		(zone
			(layer "B.Cu")
			(hatch none 0.5)
			(connect_pads
				(clearance 0)
			)
			(min_thickness 0.25)
			(keepout
				(tracks not_allowed)
				(vias allowed)
				(pads allowed)
				(copperpour not_allowed)
				(footprints allowed)
			)
			(placement
				(enabled no)
				(sheetname "")
			)
			(fill
				(thermal_gap 0.5)
				(thermal_bridge_width 0.5)
				(island_removal_mode 0)
			)
			(polygon
				(pts
					(xy 346.199206 3.329178) (xy 346.961206 3.329178) (xy 346.961206 2.059178) (xy 346.199206 2.059178)
				)
			)
		)
	)
	(footprint ""
		(layer "B.Cu")
		(at 205.74 -105.537 -90)
		(property "Reference" "R6N11"
			(at 0 0 90)
			(layer "B.SilkS")
			(hide yes)
			(effects
				(font
					(size 1.27 1.27)
				)
				(justify mirror)
			)
		)
		(property "Value" ""
			(at 0 0 90)
			(layer "B.Fab")
			(effects
				(font
					(size 1.27 1.27)
				)
				(justify mirror)
			)
		)
		(duplicate_pad_numbers_are_jumpers no)
		(fp_poly
			(pts
				(xy 0.2794 -0.1016) (xy -0.2794 -0.1016) (xy -0.2794 0.9906) (xy 0.2794 0.9906)
			)
			(stroke
				(width 0)
				(type default)
			)
			(fill no)
			(layer "B.CrtYd")
		)
		(fp_line
			(start -0.2794 0.9906)
			(end -0.2794 -0.1016)
			(stroke
				(width 0.1)
				(type default)
			)
			(layer "B.Fab")
		)
		(fp_line
			(start 0.2794 0.9906)
			(end -0.2794 0.9906)
			(stroke
				(width 0.1)
				(type default)
			)
			(layer "B.Fab")
		)
		(fp_line
			(start -0.2794 -0.1016)
			(end 0.2794 -0.1016)
			(stroke
				(width 0.1)
				(type default)
			)
			(layer "B.Fab")
		)
		(fp_line
			(start 0.2794 -0.1016)
			(end 0.2794 0.9906)
			(stroke
				(width 0.1)
				(type default)
			)
			(layer "B.Fab")
		)
		(pad "1" smd rect
			(at 0 0 90)
			(size 0.508 0.508)
			(layers "B.Cu" "B.Mask" "B.Paste")
			(net "SVID_DIO0_CPU0")
		)
		(pad "2" smd rect
			(at 0 0.889 90)
			(size 0.508 0.508)
			(layers "B.Cu" "B.Mask" "B.Paste")
			(net "SVID_DIO0_CPU0_R")
		)
		(zone
			(layer "B.Cu")
			(hatch none 0.5)
			(connect_pads
				(clearance 0)
			)
			(min_thickness 0.25)
			(keepout
				(tracks not_allowed)
				(vias allowed)
				(pads allowed)
				(copperpour not_allowed)
				(footprints allowed)
			)
			(placement
				(enabled no)
				(sheetname "")
			)
			(fill
				(thermal_gap 0.5)
				(thermal_bridge_width 0.5)
				(island_removal_mode 0)
			)
			(polygon
				(pts
					(xy 205.105 -105.283) (xy 205.105 -105.791) (xy 205.486 -105.791) (xy 205.486 -105.283)
				)
			)
		)
		(zone
			(layer "B.Cu")
			(hatch none 0.5)
			(connect_pads
				(clearance 0)
			)
			(min_thickness 0.25)
			(keepout
				(tracks allowed)
				(vias not_allowed)
				(pads allowed)
				(copperpour not_allowed)
				(footprints allowed)
			)
			(placement
				(enabled no)
				(sheetname "")
			)
			(fill
				(thermal_gap 0.5)
				(thermal_bridge_width 0.5)
				(island_removal_mode 0)
			)
			(polygon
				(pts
					(xy 205.486 -105.283) (xy 205.486 -105.791) (xy 205.105 -105.791) (xy 205.105 -105.283)
				)
			)
		)
	)
	(footprint ""
		(layer "B.Cu")
		(at 333.659226 -39.539418 90)
		(property "Reference" "C3T1"
			(at 0 0 90)
			(layer "B.SilkS")
			(hide yes)
			(effects
				(font
					(size 1.27 1.27)
				)
				(justify mirror)
			)
		)
		(property "Value" ""
			(at 0 0 90)
			(layer "B.Fab")
			(effects
				(font
					(size 1.27 1.27)
				)
				(justify mirror)
			)
		)
		(duplicate_pad_numbers_are_jumpers no)
		(fp_rect
			(start 0.500126 1.598422)
			(end -0.500126 -0.201422)
			(stroke
				(width 0)
				(type default)
			)
			(fill no)
			(layer "B.CrtYd")
		)
		(fp_line
			(start 0.500126 -0.201422)
			(end -0.500126 -0.201422)
			(stroke
				(width 0.1)
				(type default)
			)
			(layer "B.Fab")
		)
		(fp_line
			(start -0.500126 -0.201422)
			(end -0.500126 1.598422)
			(stroke
				(width 0.1)
				(type default)
			)
			(layer "B.Fab")
		)
		(fp_line
			(start 0.500126 1.598422)
			(end 0.500126 -0.201422)
			(stroke
				(width 0.1)
				(type default)
			)
			(layer "B.Fab")
		)
		(fp_line
			(start -0.500126 1.598422)
			(end 0.500126 1.598422)
			(stroke
				(width 0.1)
				(type default)
			)
			(layer "B.Fab")
		)
		(pad "1" smd rect
			(at 0 0)
			(size 0.889 0.9906)
			(layers "B.Cu" "B.Mask" "B.Paste")
			(net "P1V8_MCP_CPU0")
		)
		(pad "2" smd rect
			(at 0 1.397)
			(size 0.889 0.9906)
			(layers "B.Cu" "B.Mask" "B.Paste")
			(net "GND")
		)
		(zone
			(layer "B.Cu")
			(hatch none 0.5)
			(connect_pads
				(clearance 0)
			)
			(min_thickness 0.25)
			(keepout
				(tracks not_allowed)
				(vias allowed)
				(pads allowed)
				(copperpour not_allowed)
				(footprints allowed)
			)
			(placement
				(enabled no)
				(sheetname "")
			)
			(fill
				(thermal_gap 0.5)
				(thermal_bridge_width 0.5)
				(island_removal_mode 0)
			)
			(polygon
				(pts
					(xy 334.611726 -40.034718) (xy 334.103726 -40.034718) (xy 334.103726 -39.044118) (xy 334.611726 -39.044118)
				)
			)
		)
		(zone
			(layer "B.Cu")
			(hatch none 0.5)
			(connect_pads
				(clearance 0)
			)
			(min_thickness 0.25)
			(keepout
				(tracks allowed)
				(vias not_allowed)
				(pads allowed)
				(copperpour not_allowed)
				(footprints allowed)
			)
			(placement
				(enabled no)
				(sheetname "")
			)
			(fill
				(thermal_gap 0.5)
				(thermal_bridge_width 0.5)
				(island_removal_mode 0)
			)
			(polygon
				(pts
					(xy 334.611726 -40.034718) (xy 334.103726 -40.034718) (xy 334.103726 -39.044118) (xy 334.611726 -39.044118)
				)
			)
		)
	)
)
